# T6G (Grand Teton) — schematic netlist excerpt (pin names and nets, part order shuffled) for the footprints in the layout excerpt that follows; sources: Cadence DE-HDL packaged netlist, KiCad conversion of 04192023_DAF0TMB3IC0_F0TG_MB_C_brd_V02_OCP.brd

C162  Q_CAP  10UF 25V 10% X6S  pkg C0805  page 94 : A = P12V_MEM_CPU0 ; B = GND

U96  PCA9617ADP  IC  pkg TSSOP8_3XB  page 160
  VCCA  = PVDD18_S5_P0
  SCLA  = SMB_CPU0_CPU1_SEC_SCL_R1
  SDAA  = SMB_CPU0_CPU1_SEC_SDA_R1
  GND  = GND
  EN  = PU_U96_EN
  SDAB  = SMB_CPU0_CPU1_SEC_SDA
  SCLB  = SMB_CPU0_CPU1_SEC_SCL
  VCCB  = P3V3_AUX

PC145_6  Q_CAP  22UF 16V 20% X6S  pkg C0805  page 220 : A = SW_P12V_AUX_PVDDCR_CPU1_P1_FLT ; B = GND

(kicad_pcb
	(version 20260206)
	(generator "pcbnew")
	(generator_version "10.0")
	(general
		(thickness 1.6)
		(legacy_teardrops no)
	)
	(paper "A4")
	(title_block
		(title "04192023_DAF0TMB3IC0_F0TG_MB_C_brd_V02_OCP.brd")
		(comment 1 "Grand Teton / footprints 6323-6325 of 8354")
	)
	(layers
		(0 "F.Cu" signal "TOP")
		(4 "In1.Cu" signal "GND")
		(6 "In2.Cu" signal "IN1")
		(8 "In3.Cu" signal "GND1")
		(10 "In4.Cu" signal "IN2")
		(12 "In5.Cu" signal "GND2")
		(14 "In6.Cu" signal "IN3")
		(16 "In7.Cu" signal "GND3")
		(18 "In8.Cu" signal "VCC")
		(20 "In9.Cu" signal "VCC1")
		(22 "In10.Cu" signal "GND4")
		(24 "In11.Cu" signal "IN4")
		(26 "In12.Cu" signal "GND5")
		(28 "In13.Cu" signal "IN5")
		(30 "In14.Cu" signal "GND6")
		(32 "In15.Cu" signal "IN6")
		(34 "In16.Cu" signal "GND7")
		(2 "B.Cu" signal "BOTTOM")
		(9 "F.Adhes" user "F.Adhesive")
		(11 "B.Adhes" user "B.Adhesive")
		(13 "F.Paste" user "Package Geometry/Pastemask Top")
		(15 "B.Paste" user "Package Geometry/Pastemask Bottom")
		(5 "F.SilkS" user "Ref Des/Silkscreen Top")
		(7 "B.SilkS" user "Ref Des/Silkscreen Bottom")
		(1 "F.Mask" user "Board Geometry/Soldermask Top")
		(3 "B.Mask" user "Board Geometry/Soldermask Bottom")
		(17 "Dwgs.User" user "User.Drawings")
		(19 "Cmts.User" user "User.Comments")
		(21 "Eco1.User" user "User.Eco1")
		(23 "Eco2.User" user "User.Eco2")
		(25 "Edge.Cuts" user "Board Geometry/Outline")
		(27 "Margin" user)
		(31 "F.CrtYd" user "Package Geometry/Place Bound Top")
		(29 "B.CrtYd" user "Package Geometry/Place Bound Bottom")
		(35 "F.Fab" user "Ref Des/Assembly Top")
		(33 "B.Fab" user "Ref Des/Assembly Bottom")
	)
	(footprint ""
		(layer "B.Cu")
		(at 106.978958 -340.007194 90)
		(property "Reference" "PC145_6"
			(at 0 0 90)
			(layer "B.SilkS")
			(hide yes)
			(effects
				(font
					(size 1.27 1.27)
				)
				(justify mirror)
			)
		)
		(property "Value" ""
			(at 0 0 90)
			(layer "B.Fab")
			(effects
				(font
					(size 1.27 1.27)
				)
				(justify mirror)
			)
		)
		(duplicate_pad_numbers_are_jumpers no)
		(fp_line
			(start 1.524 -0.762)
			(end -1.524 -0.762)
			(stroke
				(width 0.1524)
				(type default)
			)
			(layer "B.SilkS")
		)
		(fp_line
			(start -1.524 -0.762)
			(end -1.524 0.762)
			(stroke
				(width 0.1524)
				(type default)
			)
			(layer "B.SilkS")
		)
		(fp_line
			(start 1.524 0.762)
			(end 1.524 -0.762)
			(stroke
				(width 0.1524)
				(type default)
			)
			(layer "B.SilkS")
		)
		(fp_line
			(start -1.524 0.762)
			(end 1.524 0.762)
			(stroke
				(width 0.1524)
				(type default)
			)
			(layer "B.SilkS")
		)
		(fp_line
			(start 1.1049 -0.724916)
			(end 1.1049 0.724916)
			(stroke
				(width 0.1)
				(type default)
			)
			(layer "B.Fab")
		)
		(fp_line
			(start -1.1049 -0.724916)
			(end 1.1049 -0.724916)
			(stroke
				(width 0.1)
				(type default)
			)
			(layer "B.Fab")
		)
		(fp_line
			(start 1.1049 0.724916)
			(end -1.1049 0.724916)
			(stroke
				(width 0.1)
				(type default)
			)
			(layer "B.Fab")
		)
		(fp_line
			(start -1.1049 0.724916)
			(end -1.1049 -0.724916)
			(stroke
				(width 0.1)
				(type default)
			)
			(layer "B.Fab")
		)
		(pad "1" smd rect
			(at 0.889 0 90)
			(size 1.016 1.27)
			(layers "B.Cu" "B.Mask" "B.Paste")
			(net "SW_P12V_AUX_PVDDCR_CPU1_P1_FLT")
		)
		(pad "2" smd rect
			(at -0.889 0 90)
			(size 1.016 1.27)
			(layers "B.Cu" "B.Mask" "B.Paste")
			(net "GND")
		)
	)
	(footprint ""
		(layer "B.Cu")
		(at 427.456092 -192.660016 180)
		(property "Reference" "C162"
			(at 0 0 0)
			(layer "B.SilkS")
			(hide yes)
			(effects
				(font
					(size 1.27 1.27)
				)
				(justify mirror)
			)
		)
		(property "Value" ""
			(at 0 0 0)
			(layer "B.Fab")
			(effects
				(font
					(size 1.27 1.27)
				)
				(justify mirror)
			)
		)
		(duplicate_pad_numbers_are_jumpers no)
		(fp_line
			(start 1.524 0.762)
			(end 1.524 -0.762)
			(stroke
				(width 0.1524)
				(type default)
			)
			(layer "B.SilkS")
		)
		(fp_line
			(start 1.524 -0.762)
			(end -1.524 -0.762)
			(stroke
				(width 0.1524)
				(type default)
			)
			(layer "B.SilkS")
		)
		(fp_line
			(start -1.524 0.762)
			(end 1.524 0.762)
			(stroke
				(width 0.1524)
				(type default)
			)
			(layer "B.SilkS")
		)
		(fp_line
			(start -1.524 -0.762)
			(end -1.524 0.762)
			(stroke
				(width 0.1524)
				(type default)
			)
			(layer "B.SilkS")
		)
		(fp_line
			(start 1.1049 0.724916)
			(end -1.1049 0.724916)
			(stroke
				(width 0.1)
				(type default)
			)
			(layer "B.Fab")
		)
		(fp_line
			(start 1.1049 -0.724916)
			(end 1.1049 0.724916)
			(stroke
				(width 0.1)
				(type default)
			)
			(layer "B.Fab")
		)
		(fp_line
			(start -1.1049 0.724916)
			(end -1.1049 -0.724916)
			(stroke
				(width 0.1)
				(type default)
			)
			(layer "B.Fab")
		)
		(fp_line
			(start -1.1049 -0.724916)
			(end 1.1049 -0.724916)
			(stroke
				(width 0.1)
				(type default)
			)
			(layer "B.Fab")
		)
		(pad "1" smd rect
			(at 0.889 0 180)
			(size 1.016 1.27)
			(layers "B.Cu" "B.Mask" "B.Paste")
			(net "P12V_MEM_CPU0")
		)
		(pad "2" smd rect
			(at -0.889 0 180)
			(size 1.016 1.27)
			(layers "B.Cu" "B.Mask" "B.Paste")
			(net "GND")
		)
	)
	(footprint ""
		(layer "B.Cu")
		(at 243.586 -223.139 90)
		(property "Reference" "U96"
			(at -1.194562 3.014472 270)
			(unlocked yes)
			(layer "B.SilkS")
			(effects
				(font
					(size 0.7874 0.5842)
					(thickness 0.1524)
				)
				(justify left mirror)
			)
		)
		(property "Value" ""
			(at 0 0 90)
			(layer "B.Fab")
			(effects
				(font
					(size 1.27 1.27)
				)
				(justify mirror)
			)
		)
		(duplicate_pad_numbers_are_jumpers no)
		(fp_line
			(start 1.463548 -1.549908)
			(end 0.787908 -1.549908)
			(stroke
				(width 0.1524)
				(type default)
			)
			(layer "B.SilkS")
		)
		(fp_line
			(start 0.787908 -1.549908)
			(end 0 -0.762)
			(stroke
				(width 0.1524)
				(type default)
			)
			(layer "B.SilkS")
		)
		(fp_line
			(start -0.762 -1.549908)
			(end -1.463548 -1.549908)
			(stroke
				(width 0.1524)
				(type default)
			)
			(layer "B.SilkS")
		)
		(fp_line
			(start -1.463548 -1.549908)
			(end -1.463548 1.549908)
			(stroke
				(width 0.1524)
				(type default)
			)
			(layer "B.SilkS")
		)
		(fp_line
			(start 0 -0.762)
			(end -0.762 -1.549908)
			(stroke
				(width 0.1524)
				(type default)
			)
			(layer "B.SilkS")
		)
		(fp_line
			(start 1.463548 1.549908)
			(end 1.463548 -1.549908)
			(stroke
				(width 0.1524)
				(type default)
			)
			(layer "B.SilkS")
		)
		(fp_line
			(start -1.463548 1.549908)
			(end 1.463548 1.549908)
			(stroke
				(width 0.1524)
				(type default)
			)
			(layer "B.SilkS")
		)
		(fp_poly
			(pts
				(xy 3.4417 -0.959866) (xy 3.4417 -1.579626) (xy 2.82194 -1.269746)
			)
			(stroke
				(width 0)
				(type default)
			)
			(fill yes)
			(layer "B.SilkS")
		)
		(fp_line
			(start 1.549908 -1.549908)
			(end -1.549908 -1.549908)
			(stroke
				(width 0.1)
				(type default)
			)
			(layer "B.Fab")
		)
		(fp_line
			(start -1.549908 -1.549908)
			(end -1.549908 1.549908)
			(stroke
				(width 0.1)
				(type default)
			)
			(layer "B.Fab")
		)
		(fp_line
			(start 1.549908 1.549908)
			(end 1.549908 -1.549908)
			(stroke
				(width 0.1)
				(type default)
			)
			(layer "B.Fab")
		)
		(fp_line
			(start -1.549908 1.549908)
			(end 1.549908 1.549908)
			(stroke
				(width 0.1)
				(type default)
			)
			(layer "B.Fab")
		)
		(fp_poly
			(pts
				(xy 3.4798 -1.359916) (xy 2.86004 -1.050036) (xy 3.4798 -0.740156)
			)
			(stroke
				(width 0)
				(type default)
			)
			(fill yes)
			(layer "B.Fab")
		)
		(pad "1" smd rect
			(at 2.175002 -1.050036 180)
			(size 0.6096 1.1684)
			(layers "B.Cu" "B.Mask" "B.Paste")
			(net "PVDD18_S5_P0")
		)
		(pad "2" smd rect
			(at 2.175002 -0.32512 180)
			(size 0.4318 1.1684)
			(layers "B.Cu" "B.Mask" "B.Paste")
			(net "SMB_CPU0_CPU1_SEC_SCL_R1")
		)
		(pad "3" smd rect
			(at 2.175002 0.32512 180)
			(size 0.4318 1.1684)
			(layers "B.Cu" "B.Mask" "B.Paste")
			(net "SMB_CPU0_CPU1_SEC_SDA_R1")
		)
		(pad "4" smd rect
			(at 2.175002 1.050036 180)
			(size 0.6096 1.1684)
			(layers "B.Cu" "B.Mask" "B.Paste")
			(net "GND")
		)
		(pad "5" smd rect
			(at -2.175002 1.050036 180)
			(size 0.6096 1.1684)
			(layers "B.Cu" "B.Mask" "B.Paste")
			(net "PU_U96_EN")
		)
		(pad "6" smd rect
			(at -2.175002 0.32512 180)
			(size 0.4318 1.1684)
			(layers "B.Cu" "B.Mask" "B.Paste")
			(net "SMB_CPU0_CPU1_SEC_SDA")
		)
		(pad "7" smd rect
			(at -2.175002 -0.32512 180)
			(size 0.4318 1.1684)
			(layers "B.Cu" "B.Mask" "B.Paste")
			(net "SMB_CPU0_CPU1_SEC_SCL")
		)
		(pad "8" smd rect
			(at -2.175002 -1.050036 180)
			(size 0.6096 1.1684)
			(layers "B.Cu" "B.Mask" "B.Paste")
			(net "P3V3_AUX")
		)
	)
)
